# T6G (Grand Teton) — schematic netlist excerpt (pin names and nets, part order shuffled) for the footprints in the layout excerpt that follows; sources: Cadence DE-HDL packaged netlist, KiCad conversion of 04192023_DAF0TMB3IC0_F0TG_MB_C_brd_V02_OCP.brd

R565  Q_RES  0 5% CHIP  pkg 0402LF  page 159 : A = I3C_0_SPD_DDRAF_CPU1_SDA ; B = I3C_0_SPD_DDRAF_CPU1_R_SDA
C1997  Q_CAP  0.1UF 25V 10% X7R  pkg 0402  page 148 : A = P3V3_AUX ; B = GND

(kicad_pcb
	(version 20260206)
	(generator "pcbnew")
	(generator_version "10.0")
	(general
		(thickness 1.6)
		(legacy_teardrops no)
	)
	(paper "A4")
	(title_block
		(title "04192023_DAF0TMB3IC0_F0TG_MB_C_brd_V02_OCP.brd")
		(comment 1 "Grand Teton / footprints 2112-2113 of 8354")
	)
	(layers
		(0 "F.Cu" signal "TOP")
		(4 "In1.Cu" signal "GND")
		(6 "In2.Cu" signal "IN1")
		(8 "In3.Cu" signal "GND1")
		(10 "In4.Cu" signal "IN2")
		(12 "In5.Cu" signal "GND2")
		(14 "In6.Cu" signal "IN3")
		(16 "In7.Cu" signal "GND3")
		(18 "In8.Cu" signal "VCC")
		(20 "In9.Cu" signal "VCC1")
		(22 "In10.Cu" signal "GND4")
		(24 "In11.Cu" signal "IN4")
		(26 "In12.Cu" signal "GND5")
		(28 "In13.Cu" signal "IN5")
		(30 "In14.Cu" signal "GND6")
		(32 "In15.Cu" signal "IN6")
		(34 "In16.Cu" signal "GND7")
		(2 "B.Cu" signal "BOTTOM")
		(9 "F.Adhes" user "F.Adhesive")
		(11 "B.Adhes" user "B.Adhesive")
		(13 "F.Paste" user "Package Geometry/Pastemask Top")
		(15 "B.Paste" user "Package Geometry/Pastemask Bottom")
		(5 "F.SilkS" user "Ref Des/Silkscreen Top")
		(7 "B.SilkS" user "Ref Des/Silkscreen Bottom")
		(1 "F.Mask" user "Board Geometry/Soldermask Top")
		(3 "B.Mask" user "Board Geometry/Soldermask Bottom")
		(17 "Dwgs.User" user "User.Drawings")
		(19 "Cmts.User" user "User.Comments")
		(21 "Eco1.User" user "User.Eco1")
		(23 "Eco2.User" user "User.Eco2")
		(25 "Edge.Cuts" user "Board Geometry/Outline")
		(27 "Margin" user)
		(31 "F.CrtYd" user "Package Geometry/Place Bound Top")
		(29 "B.CrtYd" user "Package Geometry/Place Bound Bottom")
		(35 "F.Fab" user "Ref Des/Assembly Top")
		(33 "B.Fab" user "Ref Des/Assembly Bottom")
	)
	(footprint ""
		(layer "F.Cu")
		(at 215.98128 -41.341548)
		(property "Reference" "C1997"
			(at 0 0 0)
			(layer "F.SilkS")
			(hide yes)
			(effects
				(font
					(size 1.27 1.27)
				)
			)
		)
		(property "Value" ""
			(at 0 0 0)
			(layer "F.Fab")
			(effects
				(font
					(size 1.27 1.27)
				)
			)
		)
		(duplicate_pad_numbers_are_jumpers no)
		(fp_line
			(start -0.7874 -0.4064)
			(end 0.7874 -0.4064)
			(stroke
				(width 0.1524)
				(type default)
			)
			(layer "F.SilkS")
		)
		(fp_line
			(start -0.7874 0.4064)
			(end -0.7874 -0.4064)
			(stroke
				(width 0.1524)
				(type default)
			)
			(layer "F.SilkS")
		)
		(fp_line
			(start 0.7874 -0.4064)
			(end 0.7874 0.4064)
			(stroke
				(width 0.1524)
				(type default)
			)
			(layer "F.SilkS")
		)
		(fp_line
			(start 0.7874 0.4064)
			(end -0.7874 0.4064)
			(stroke
				(width 0.1524)
				(type default)
			)
			(layer "F.SilkS")
		)
		(fp_line
			(start -0.67945 -0.305054)
			(end -0.12065 -0.305054)
			(stroke
				(width 0.1)
				(type default)
			)
			(layer "F.Fab")
		)
		(fp_line
			(start -0.67945 0.3048)
			(end -0.67945 -0.305054)
			(stroke
				(width 0.1)
				(type default)
			)
			(layer "F.Fab")
		)
		(fp_line
			(start -0.12065 -0.305054)
			(end -0.12065 -0.2794)
			(stroke
				(width 0.1)
				(type default)
			)
			(layer "F.Fab")
		)
		(fp_line
			(start -0.12065 -0.2794)
			(end 0.12065 -0.2794)
			(stroke
				(width 0.1)
				(type default)
			)
			(layer "F.Fab")
		)
		(fp_line
			(start -0.12065 0.2794)
			(end -0.12065 0.3048)
			(stroke
				(width 0.1)
				(type default)
			)
			(layer "F.Fab")
		)
		(fp_line
			(start -0.12065 0.3048)
			(end -0.67945 0.3048)
			(stroke
				(width 0.1)
				(type default)
			)
			(layer "F.Fab")
		)
		(fp_line
			(start 0.120396 0.2794)
			(end -0.12065 0.2794)
			(stroke
				(width 0.1)
				(type default)
			)
			(layer "F.Fab")
		)
		(fp_line
			(start 0.120396 0.3048)
			(end 0.120396 0.2794)
			(stroke
				(width 0.1)
				(type default)
			)
			(layer "F.Fab")
		)
		(fp_line
			(start 0.12065 -0.3048)
			(end 0.67945 -0.3048)
			(stroke
				(width 0.1)
				(type default)
			)
			(layer "F.Fab")
		)
		(fp_line
			(start 0.12065 -0.2794)
			(end 0.12065 -0.3048)
			(stroke
				(width 0.1)
				(type default)
			)
			(layer "F.Fab")
		)
		(fp_line
			(start 0.67945 -0.3048)
			(end 0.67945 0.3048)
			(stroke
				(width 0.1)
				(type default)
			)
			(layer "F.Fab")
		)
		(fp_line
			(start 0.67945 0.3048)
			(end 0.120396 0.3048)
			(stroke
				(width 0.1)
				(type default)
			)
			(layer "F.Fab")
		)
		(pad "1" smd circle
			(at -0.40005 0)
			(size 0 0)
			(layers "F.Cu" "F.Mask" "F.Paste")
			(net "P3V3_AUX")
		)
		(pad "2" smd circle
			(at 0.40005 0)
			(size 0 0)
			(layers "F.Cu" "F.Mask" "F.Paste")
			(net "GND")
		)
	)
	(footprint ""
		(layer "F.Cu")
		(at 42.672 -171.831)
		(property "Reference" "R565"
			(at 0 0 0)
			(layer "F.SilkS")
			(hide yes)
			(effects
				(font
					(size 1.27 1.27)
				)
			)
		)
		(property "Value" ""
			(at 0 0 0)
			(layer "F.Fab")
			(effects
				(font
					(size 1.27 1.27)
				)
			)
		)
		(duplicate_pad_numbers_are_jumpers no)
		(fp_line
			(start -0.7874 -0.4064)
			(end 0.7874 -0.4064)
			(stroke
				(width 0.1524)
				(type default)
			)
			(layer "F.SilkS")
		)
		(fp_line
			(start -0.7874 0.4064)
			(end -0.7874 -0.4064)
			(stroke
				(width 0.1524)
				(type default)
			)
			(layer "F.SilkS")
		)
		(fp_line
			(start 0.7874 -0.4064)
			(end 0.7874 0.4064)
			(stroke
				(width 0.1524)
				(type default)
			)
			(layer "F.SilkS")
		)
		(fp_line
			(start 0.7874 0.4064)
			(end -0.7874 0.4064)
			(stroke
				(width 0.1524)
				(type default)
			)
			(layer "F.SilkS")
		)
		(fp_line
			(start -0.67945 -0.305054)
			(end -0.12065 -0.305054)
			(stroke
				(width 0.1)
				(type default)
			)
			(layer "F.Fab")
		)
		(fp_line
			(start -0.67945 0.3048)
			(end -0.67945 -0.305054)
			(stroke
				(width 0.1)
				(type default)
			)
			(layer "F.Fab")
		)
		(fp_line
			(start -0.12065 -0.305054)
			(end -0.12065 -0.2794)
			(stroke
				(width 0.1)
				(type default)
			)
			(layer "F.Fab")
		)
		(fp_line
			(start -0.12065 -0.2794)
			(end 0.12065 -0.2794)
			(stroke
				(width 0.1)
				(type default)
			)
			(layer "F.Fab")
		)
		(fp_line
			(start -0.12065 0.2794)
			(end -0.12065 0.3048)
			(stroke
				(width 0.1)
				(type default)
			)
			(layer "F.Fab")
		)
		(fp_line
			(start -0.12065 0.3048)
			(end -0.67945 0.3048)
			(stroke
				(width 0.1)
				(type default)
			)
			(layer "F.Fab")
		)
		(fp_line
			(start 0.120396 0.2794)
			(end -0.12065 0.2794)
			(stroke
				(width 0.1)
				(type default)
			)
			(layer "F.Fab")
		)
		(fp_line
			(start 0.120396 0.3048)
			(end 0.120396 0.2794)
			(stroke
				(width 0.1)
				(type default)
			)
			(layer "F.Fab")
		)
		(fp_line
			(start 0.12065 -0.3048)
			(end 0.67945 -0.3048)
			(stroke
				(width 0.1)
				(type default)
			)
			(layer "F.Fab")
		)
		(fp_line
			(start 0.12065 -0.2794)
			(end 0.12065 -0.3048)
			(stroke
				(width 0.1)
				(type default)
			)
			(layer "F.Fab")
		)
		(fp_line
			(start 0.67945 -0.3048)
			(end 0.67945 0.3048)
			(stroke
				(width 0.1)
				(type default)
			)
			(layer "F.Fab")
		)
		(fp_line
			(start 0.67945 0.3048)
			(end 0.120396 0.3048)
			(stroke
				(width 0.1)
				(type default)
			)
			(layer "F.Fab")
		)
		(pad "1" smd rect
			(at -0.40005 0 180)
			(size 0.4572 0.508)
			(layers "F.Cu" "F.Mask" "F.Paste")
			(net "I3C_0_SPD_DDRAF_CPU1_SDA")
		)
		(pad "2" smd rect
			(at 0.40005 0 180)
			(size 0.4572 0.508)
			(layers "F.Cu" "F.Mask" "F.Paste")
			(net "I3C_0_SPD_DDRAF_CPU1_R_SDA")
		)
	)
)
